G04 ================== begin FILE IDENTIFICATION RECORD ==================*
G04 Layout Name:  9051_F0T_Panel_BD_Front_D_v02_20221209_1310.brd*
G04 Film Name:    smt.art*
G04 File Format:  Gerber RS274X*
G04 File Origin:  Cadence Allegro 17.2-S081*
G04 Origin Date:  Mon Dec 12 15:51:17 2022*
G04 *
G04 Layer:  DRAWING FORMAT/TITLE_BLOCK_A*
G04 Layer:  DRAWING FORMAT/TITLE_BLOCK*
G04 Layer:  VIA CLASS/SOLDERMASK_TOP*
G04 Layer:  PIN/SOLDERMASK_TOP*
G04 Layer:  PACKAGE GEOMETRY/SOLDERMASK_TOP*
G04 Layer:  MANUFACTURING/PHOTOPLOT_OUTLINE*
G04 Layer:  DRAWING FORMAT/TITLE_DATA_SMT*
G04 Layer:  BOARD GEOMETRY/SOLDERMASK_TOP*
G04 *
G04 Offset:    (0.00 0.00)*
G04 Mirror:    No*
G04 Mode:      Positive*
G04 Rotation:  0*
G04 FullContactRelief:  No*
G04 UndefLineWidth:     6.00*
G04 ================== end FILE IDENTIFICATION RECORD ====================*
%FSLAX25Y25*MOIN*%
%IR0*IPPOS*OFA0.00000B0.00000*MIA0B0*SFA1.00000B1.00000*%
%ADD40O,.056X.107*%
%ADD52C,.061*%
%ADD18C,.052*%
%ADD11C,.034*%
%ADD38C,.072*%
%ADD39C,.046*%
%ADD41C,.048*%
%ADD51C,.085*%
%ADD26C,.058*%
%AMMACRO53*
4,1,8,.08,-.0445,
-.08,-.0445,
-.08,.0445,
-.0216,.0445,
-.0216,.0165,
.0216,.0165,
.0216,.0445,
.08,.0445,
.08,-.0445,
0.0*
%
%ADD53MACRO53*%
%ADD10R,.052X.052*%
%ADD56C,.0395*%
%ADD43R,.048X.048*%
%ADD57C,.0785*%
%ADD29R,.058X.058*%
%AMMACRO36*
4,1,28,-.00589,-.01192,
-.006913,-.011842,
-.007907,-.011587,
-.008842,-.011163,
-.009688,-.010584,
-.010422,-.009866,
-.011019,-.009032,
-.011463,-.008107,
-.011739,-.007119,
-.01184,-.006097,
-.01184,-.00603,
-.01184,.00148,
-.00948,.00148,
-.00948,.01191,
.00948,.01191,
.00948,.00148,
.01184,.00148,
.01184,-.00603,
.011751,-.007052,
.011486,-.008044,
.011053,-.008974,
.010465,-.009815,
.00974,-.010541,
.0089,-.01113,
.00797,-.011564,
.006979,-.01183,
.005957,-.01192,
.00589,-.01192,
-.00589,-.01192,
0.0*
%
%ADD36MACRO36*%
%AMMACRO14*
4,1,28,-.01192,.00589,
-.011842,.006913,
-.011587,.007907,
-.011163,.008842,
-.010584,.009688,
-.009866,.010422,
-.009032,.011019,
-.008107,.011463,
-.007119,.011739,
-.006097,.01184,
-.00603,.01184,
.00148,.01184,
.00148,.00948,
.01191,.00948,
.01191,-.00948,
.00148,-.00948,
.00148,-.01184,
-.00603,-.01184,
-.007052,-.011751,
-.008044,-.011486,
-.008974,-.011053,
-.009815,-.010465,
-.010541,-.00974,
-.01113,-.0089,
-.011564,-.00797,
-.01183,-.006979,
-.01192,-.005957,
-.01192,-.00589,
-.01192,.00589,
0.0*
%
%ADD14MACRO14*%
%AMMACRO35*
4,1,28,.0059,.01191,
.006923,.01183,
.007916,.011573,
.00885,.011148,
.009696,.010567,
.010428,.009849,
.011024,.009013,
.011466,.008088,
.011741,.007099,
.01184,.006078,
.01184,.00602,
.01184,-.00149,
.00948,-.00149,
.00948,-.01192,
-.00948,-.01192,
-.00948,-.00149,
-.01184,-.00149,
-.01184,.00602,
-.011751,.007042,
-.011486,.008033,
-.011053,.008964,
-.010465,.009805,
-.00974,.010531,
-.0089,.01112,
-.007971,.011554,
-.00698,.01182,
-.005958,.01191,
-.0059,.01191,
.0059,.01191,
0.0*
%
%ADD35MACRO35*%
%AMMACRO13*
4,1,28,.01191,-.0059,
.01183,-.006923,
.011573,-.007916,
.011148,-.00885,
.010567,-.009696,
.009849,-.010428,
.009013,-.011024,
.008088,-.011466,
.007099,-.011741,
.006078,-.01184,
.00602,-.01184,
-.00149,-.01184,
-.00149,-.00948,
-.01192,-.00948,
-.01192,.00948,
-.00149,.00948,
-.00149,.01184,
.00602,.01184,
.007042,.011751,
.008033,.011486,
.008964,.011053,
.009805,.010465,
.010531,.00974,
.01112,.0089,
.011554,.007971,
.01182,.00698,
.01191,.005958,
.01191,.0059,
.01191,-.0059,
0.0*
%
%ADD13MACRO13*%
%ADD49R,.024X.022*%
%ADD34R,.044X.032*%
%ADD54R,.016X.024*%
%ADD48R,.018X.04*%
%ADD44R,.032X.044*%
%ADD28R,.021X.028*%
%ADD27R,.06X.044*%
%ADD21R,.036X.032*%
%ADD45R,.032X.028*%
%ADD24R,.058X.02*%
%ADD47R,.042X.028*%
%ADD31R,.028X.032*%
%ADD22R,.06X.028*%
%ADD50R,.044X.054*%
%ADD20R,.036X.028*%
%ADD17C,.145*%
%ADD12C,.118*%
%ADD46R,.056X.028*%
%ADD25C,.139*%
%AMMACRO55*
4,1,8,-.08,.0445,
.08,.0445,
.08,-.0445,
.0216,-.0445,
.0216,-.0165,
-.0216,-.0165,
-.0216,-.0445,
-.08,-.0445,
-.08,.0445,
0.0*
%
%ADD55MACRO55*%
%ADD37R,.019X.057*%
%ADD23R,.058X.028*%
%ADD42O,.056X.079*%
%ADD30R,.058X.048*%
%ADD19C,.178*%
%AMMACRO33*
4,1,28,.00589,.01192,
.006913,.011842,
.007907,.011587,
.008842,.011163,
.009688,.010584,
.010422,.009866,
.011019,.009032,
.011463,.008107,
.011739,.007119,
.01184,.006097,
.01184,.00603,
.01184,-.00148,
.00948,-.00148,
.00948,-.01191,
-.00948,-.01191,
-.00948,-.00148,
-.01184,-.00148,
-.01184,.00603,
-.011751,.007052,
-.011486,.008044,
-.011053,.008974,
-.010465,.009815,
-.00974,.010541,
-.0089,.01113,
-.00797,.011564,
-.006979,.01183,
-.005957,.01192,
-.00589,.01192,
.00589,.01192,
0.0*
%
%ADD33MACRO33*%
%AMMACRO16*
4,1,28,.01192,-.00589,
.011842,-.006913,
.011587,-.007907,
.011163,-.008842,
.010584,-.009688,
.009866,-.010422,
.009032,-.011019,
.008107,-.011463,
.007119,-.011739,
.006097,-.01184,
.00603,-.01184,
-.00148,-.01184,
-.00148,-.00948,
-.01191,-.00948,
-.01191,.00948,
-.00148,.00948,
-.00148,.01184,
.00603,.01184,
.007052,.011751,
.008044,.011486,
.008974,.011053,
.009815,.010465,
.010541,.00974,
.01113,.0089,
.011564,.00797,
.01183,.006979,
.01192,.005957,
.01192,.00589,
.01192,-.00589,
0.0*
%
%ADD16MACRO16*%
%AMMACRO32*
4,1,28,-.0059,-.01191,
-.006923,-.01183,
-.007916,-.011573,
-.00885,-.011148,
-.009696,-.010567,
-.010428,-.009849,
-.011024,-.009013,
-.011466,-.008088,
-.011741,-.007099,
-.01184,-.006078,
-.01184,-.00602,
-.01184,.00149,
-.00948,.00149,
-.00948,.01192,
.00948,.01192,
.00948,.00149,
.01184,.00149,
.01184,-.00602,
.011751,-.007042,
.011486,-.008033,
.011053,-.008964,
.010465,-.009805,
.00974,-.010531,
.0089,-.01112,
.007971,-.011554,
.00698,-.01182,
.005958,-.01191,
.0059,-.01191,
-.0059,-.01191,
0.0*
%
%ADD32MACRO32*%
%AMMACRO15*
4,1,28,-.01191,.0059,
-.01183,.006923,
-.011573,.007916,
-.011148,.00885,
-.010567,.009696,
-.009849,.010428,
-.009013,.011024,
-.008088,.011466,
-.007099,.011741,
-.006078,.01184,
-.00602,.01184,
.00149,.01184,
.00149,.00948,
.01192,.00948,
.01192,-.00948,
.00149,-.00948,
.00149,-.01184,
-.00602,-.01184,
-.007042,-.011751,
-.008033,-.011486,
-.008964,-.011053,
-.009805,-.010465,
-.010531,-.00974,
-.01112,-.0089,
-.011554,-.007971,
-.01182,-.00698,
-.01191,-.005958,
-.01191,-.0059,
-.01191,.0059,
0.0*
%
%ADD15MACRO15*%
%ADD58C,.02*%
%ADD59C,.006*%
%ADD60C,.1942*%
G75*
%LPD*%
G75*
G36*
G01X43901Y58661D02*
G02I-19885J0D01*
G37*
G36*
G01X17389Y85883D02*
G03I-5900J0D01*
G37*
G36*
G01X41932Y279449D02*
G02X10036I-15948J0D01*
G01Y293229D01*
G02X41932I15948J0D01*
G01Y279449D01*
G37*
G36*
G01X56900Y301000D02*
G03I-5900J0D01*
G37*
G36*
G01X110900Y234500D02*
G03I-5900J0D01*
G37*
G36*
G01X152169Y43425D02*
G02X120273I-15948J0D01*
G01Y57205D01*
G02X152169I15948J0D01*
G01Y43425D01*
G37*
G36*
G01X149019Y247543D02*
G02I-19885J0D01*
G37*
%LPC*%
G75*
G36*
G01X16921Y285904D02*
G02X35047I9063J7324D01*
G03X33700Y282093I4716J-3811D01*
G01Y279449D01*
G02X18268I-7716J0D01*
G01Y282093D01*
G03X16921Y285904I-6065J0D01*
G37*
G36*
G01X127158Y49880D02*
G02X145284I9063J7324D01*
G03X143937Y46069I4716J-3811D01*
G01Y43425D01*
G02X128505I-7716J0D01*
G01Y46069D01*
G03X127158Y49880I-6065J0D01*
G37*
G54D60*
X24016Y58661D03*
X129134Y247543D03*
%LPD*%
G75*
G54D10*
X10315Y20079D03*
X33937D03*
G54D20*
X25650Y101000D03*
X19350Y98441D03*
Y103559D03*
X25650Y112000D03*
X19350Y109441D03*
Y114559D03*
G54D11*
X13553Y48198D03*
Y69124D03*
X9218Y58661D03*
X16000Y119500D03*
X34479Y48198D03*
X24016Y43863D03*
X34479Y69124D03*
X24016Y73459D03*
X31000Y112000D03*
Y101000D03*
X22000Y190000D03*
Y201000D03*
Y196000D03*
X30000Y223500D03*
Y218500D03*
Y213500D03*
Y236500D03*
Y241500D03*
X38814Y58661D03*
X42400Y93000D03*
X51500Y105000D03*
X44500Y104000D03*
X56000Y186000D03*
Y196500D03*
Y191500D03*
X50500Y249000D03*
X79000Y223500D03*
X66000Y224500D03*
X81500Y243001D03*
X81000Y235500D03*
X66000Y229500D03*
Y239500D03*
Y234500D03*
X61256Y254000D03*
X72500Y250000D03*
X89000Y128000D03*
X82500Y262000D03*
X88500D03*
X83568Y256068D03*
X118671Y237080D03*
Y258006D03*
X114336Y247543D03*
X137500Y100000D03*
X133000Y104000D03*
X137500Y107000D03*
X139597Y237080D03*
X129134Y232745D03*
Y262341D03*
X139597Y258006D03*
X143932Y247543D03*
G54D30*
X76755Y39441D03*
Y46921D03*
G54D12*
X11489Y85883D03*
X51000Y301000D03*
X105000Y234500D03*
G54D21*
X36600Y98500D03*
Y109500D03*
X42400Y98500D03*
Y109500D03*
X63600Y37100D03*
X69400D03*
X70600Y261000D03*
X76400D03*
X65400D03*
X59600D03*
G54D22*
X28567Y186000D03*
Y191000D03*
Y196000D03*
Y201000D03*
X49433Y196000D03*
Y191000D03*
Y186000D03*
Y201000D03*
G54D31*
X78240Y72563D03*
X70760D03*
Y80437D03*
G54D13*
X13484Y114500D03*
Y103500D03*
X16984Y196000D03*
Y188000D03*
Y200000D03*
Y204000D03*
X24984Y217500D03*
Y209500D03*
Y225500D03*
X54484Y83500D03*
X69984Y67500D03*
X78484Y91000D03*
Y87000D03*
X70484Y91000D03*
X78484Y95000D03*
Y99000D03*
X70484Y95000D03*
X63984Y197500D03*
X73984Y219500D03*
X58984Y201500D03*
X73984Y227500D03*
Y231500D03*
Y223500D03*
X68984Y244500D03*
X73484Y265500D03*
X93984Y120000D03*
X117984Y126000D03*
Y130000D03*
X145984Y88000D03*
Y80000D03*
Y104000D03*
Y96000D03*
G54D40*
X87756Y47244D03*
X109095Y89370D03*
G54D32*
X59500Y57516D03*
X65000Y76016D03*
X59500Y97516D03*
X81500Y248016D03*
X85500D03*
G54D23*
X36484Y213532D03*
Y242468D03*
X59516Y213532D03*
Y242468D03*
G54D50*
X145000Y113500D03*
X138000D03*
X145000Y127500D03*
X138000D03*
X145000Y120500D03*
X138000D03*
X124000Y134500D03*
X131000D03*
X124000Y127500D03*
X131000D03*
X145000Y134500D03*
X138000D03*
G54D14*
X10517Y114500D03*
Y103500D03*
X14017Y196000D03*
Y188000D03*
Y200000D03*
Y204000D03*
X22017Y217500D03*
Y209500D03*
Y225500D03*
X51517Y83500D03*
X56017Y201500D03*
X67017Y67500D03*
X75517Y91000D03*
Y87000D03*
X67517Y91000D03*
X75517Y95000D03*
Y99000D03*
X67517Y95000D03*
X61017Y197500D03*
X71017Y219500D03*
Y227500D03*
Y231500D03*
Y223500D03*
X66017Y244500D03*
X70517Y265500D03*
X91017Y120000D03*
X115017Y126000D03*
Y130000D03*
X143017Y88000D03*
Y80000D03*
Y104000D03*
Y96000D03*
G54D41*
X101969Y52480D03*
Y68228D03*
Y60354D03*
X94882Y54449D03*
Y64291D03*
Y72165D03*
X101969Y83976D03*
Y76102D03*
G54D15*
X10516Y99500D03*
Y110500D03*
X14016Y192000D03*
Y184000D03*
X36016Y103500D03*
Y114500D03*
X22016Y221500D03*
Y213500D03*
Y229500D03*
Y241500D03*
Y233500D03*
Y237500D03*
Y245500D03*
X51516Y87500D03*
Y110000D03*
X42516Y247000D03*
X67516Y87000D03*
Y99000D03*
X61016Y177500D03*
Y181500D03*
Y185500D03*
Y193500D03*
Y189500D03*
X71016Y239500D03*
Y235500D03*
X60016Y265500D03*
X120854Y27211D03*
X143016Y92000D03*
Y84000D03*
Y76000D03*
Y108000D03*
Y100000D03*
G54D33*
X59500Y60483D03*
X65000Y78983D03*
X59500Y100483D03*
X81500Y250983D03*
X85500D03*
G54D42*
X87756Y89370D03*
X109095Y47244D03*
G54D24*
X36484Y216484D03*
Y219043D03*
Y221602D03*
Y224161D03*
Y226720D03*
Y229280D03*
Y231839D03*
Y234398D03*
Y236957D03*
Y239516D03*
X59516Y221602D03*
Y219043D03*
Y216484D03*
Y239516D03*
Y236957D03*
Y234398D03*
Y231839D03*
Y229280D03*
Y226720D03*
Y224161D03*
G54D51*
X339937Y104912D03*
X344937Y91728D03*
X349937Y104912D03*
X352033Y234525D03*
X342033D03*
X347033Y247709D03*
G54D16*
X13483Y99500D03*
Y110500D03*
X16983Y192000D03*
Y184000D03*
X24983Y221500D03*
Y213500D03*
Y229500D03*
Y241500D03*
Y233500D03*
Y237500D03*
Y245500D03*
X54483Y87500D03*
Y110000D03*
X38983Y103500D03*
Y114500D03*
X45483Y247000D03*
X70483Y87000D03*
Y99000D03*
X63983Y177500D03*
Y181500D03*
Y185500D03*
Y193500D03*
Y189500D03*
X73983Y239500D03*
Y235500D03*
X62983Y265500D03*
X123821Y27211D03*
X145983Y92000D03*
Y84000D03*
Y76000D03*
Y108000D03*
Y100000D03*
G54D25*
X25984Y279449D03*
X136221Y43425D03*
G54D34*
X77453Y80437D03*
G54D43*
X94882Y82008D03*
G54D52*
X350500Y420150D03*
X340500D03*
X350500Y445150D03*
X340500D03*
Y597350D03*
X350500D03*
X340500Y622350D03*
X350500D03*
X380000Y316336D03*
X370000D03*
X380000Y341336D03*
X370000D03*
Y597350D03*
X380000D03*
X370000Y622350D03*
X380000D03*
G54D17*
X14000Y255500D03*
X60989Y131906D03*
X134016Y147928D03*
G54D44*
X98437Y107547D03*
X128385Y76431D03*
G54D35*
X77500Y250984D03*
G54D53*
X345500Y431500D03*
X375000Y327686D03*
G54D26*
X57480Y26299D03*
X67480D03*
G54D45*
X90563Y106760D03*
Y114240D03*
X98437D03*
X120511Y75644D03*
Y83124D03*
X128385D03*
G54D27*
X59586Y43608D03*
Y51088D03*
X68248Y47348D03*
X68720Y57967D03*
X77382Y61707D03*
Y54227D03*
G54D54*
X346484Y434750D03*
X344516D03*
Y607750D03*
X346484D03*
X375984Y330936D03*
X374016D03*
Y607750D03*
X375984D03*
G54D36*
X77500Y248017D03*
G54D18*
X20315Y20079D03*
X43937D03*
G54D19*
X24016Y58661D03*
X129134Y247543D03*
G54D37*
X64764Y274803D03*
X67126D03*
X69489D03*
X71851D03*
X74213D03*
X76575D03*
X78937D03*
X64764Y284055D03*
X67126D03*
X69489D03*
X71851D03*
X74213D03*
X76575D03*
X78937D03*
X81300Y274803D03*
X83662D03*
X86024D03*
X88386D03*
X90748D03*
X93111D03*
X95473D03*
X97835D03*
X100197D03*
X81300Y284055D03*
X83662D03*
X86024D03*
X88386D03*
X90748D03*
X93111D03*
X95473D03*
X97835D03*
X100197D03*
X102559Y274803D03*
X104922D03*
X107284D03*
X102559Y284055D03*
X104922D03*
X107284D03*
G54D55*
X345500Y611000D03*
X375000D03*
G54D46*
X122983Y6716D03*
Y11716D03*
Y16716D03*
Y21716D03*
X143849Y6716D03*
Y21716D03*
Y16716D03*
Y11716D03*
G54D28*
X54059Y92260D03*
X51500D03*
X48941D03*
Y99740D03*
X51500D03*
X54059D03*
G54D47*
X121571Y112760D03*
Y116500D03*
Y120240D03*
X130429Y112760D03*
Y120240D03*
Y116500D03*
G54D29*
X77480Y26299D03*
G54D56*
X370195Y93000D03*
X380195D03*
Y247618D03*
X370195D03*
G54D38*
X64174Y294685D03*
X107874D03*
G54D48*
X126121Y90575D03*
X122775D03*
X126121Y97267D03*
X122775D03*
G54D57*
X370195Y83000D03*
X380195D03*
Y257618D03*
X370195D03*
G54D39*
X61516Y326772D03*
Y314961D03*
X110532Y326772D03*
Y314961D03*
G54D58*
G01X7879Y43D02*
X146855D01*
G01X5Y7917D02*
G03X7879Y43I7874J0D01*
G01X5Y272460D02*
Y7917D01*
G01X2170Y277884D02*
G03X5Y272460I5710J-5423D01*
G01X4336Y283307D02*
G02X2170Y277884I-7874J1D01*
G01X4336Y307130D02*
Y283307D01*
G01X12210Y315004D02*
G03X4336Y307130I0J-7874D01*
G01X42721Y315004D02*
X12210D01*
G01X50595Y322878D02*
G02X42721Y315004I-7874J0D01*
G01X50595Y331342D02*
Y322878D01*
G01X58469Y339216D02*
G03X50595Y331342I0J-7874D01*
G01X113588Y339216D02*
X58469D01*
G01X121462Y322878D02*
Y331342D01*
G01X129336Y315004D02*
G02X121462Y322878I0J7874D01*
G01Y331342D02*
G03X113588Y339216I-7874J0D01*
G01X142525Y315004D02*
G02X150399Y307130I0J-7874D01*
G01Y283307D01*
G03X152564Y277884I7874J0D01*
G01X142525Y315004D02*
X129336D01*
G01X146855Y43D02*
G03X154729Y7917I0J7874D01*
G01D02*
Y272460D01*
G01D02*
G03X152564Y277884I-7875J1D01*
G54D49*
X126121Y92117D03*
X122775D03*
X126121Y95267D03*
X122775D03*
G54D59*
G01X-117168Y-317735D02*
Y-322735D01*
G01X-118625Y-317735D02*
X-115711D01*
G01X-110801Y-322735D02*
X-113335D01*
Y-317735D01*
X-110801D01*
G01X-111815Y-320152D02*
X-113335D01*
G01X-108235Y-317735D02*
Y-322735D01*
X-105701D01*
G01X-101868Y-322902D02*
X-101995Y-322818D01*
Y-322652D01*
X-101868Y-322568D01*
X-101741Y-322652D01*
Y-322818D01*
X-101868Y-322902D01*
G01Y-320652D02*
X-101995Y-320568D01*
Y-320402D01*
X-101868Y-320318D01*
X-101741Y-320402D01*
Y-320568D01*
X-101868Y-320652D01*
G01X-97085Y-324402D02*
X-97718Y-323568D01*
X-98035Y-322735D01*
Y-319402D01*
X-97718Y-318568D01*
X-97085Y-317735D01*
G01X-91668D02*
X-92175Y-317902D01*
X-92555Y-318318D01*
X-92808Y-318818D01*
X-92998Y-319485D01*
X-93061Y-320235D01*
X-92998Y-320985D01*
X-92808Y-321652D01*
X-92555Y-322152D01*
X-92175Y-322568D01*
X-91668Y-322735D01*
X-91161Y-322568D01*
X-90781Y-322152D01*
X-90528Y-321652D01*
X-90338Y-320985D01*
X-90275Y-320235D01*
X-90338Y-319485D01*
X-90528Y-318818D01*
X-90781Y-318318D01*
X-91161Y-317902D01*
X-91668Y-317735D01*
G01X-87961Y-321735D02*
X-87581Y-322318D01*
X-87075Y-322652D01*
X-86505Y-322735D01*
X-85998Y-322652D01*
X-85491Y-322235D01*
X-85175Y-321735D01*
X-85111Y-321235D01*
X-85238Y-320652D01*
X-85681Y-320235D01*
X-86125Y-320068D01*
X-86695D01*
G01X-86125D02*
X-85745Y-319818D01*
X-85428Y-319402D01*
X-85301Y-318902D01*
X-85428Y-318402D01*
X-85745Y-317985D01*
X-86315Y-317735D01*
X-86885Y-317818D01*
X-87455Y-318152D01*
G01X-81151Y-324402D02*
X-80518Y-323568D01*
X-80201Y-322735D01*
Y-319402D01*
X-80518Y-318568D01*
X-81151Y-317735D01*
G01X-77761Y-321735D02*
X-77381Y-322318D01*
X-76875Y-322652D01*
X-76305Y-322735D01*
X-75798Y-322652D01*
X-75291Y-322235D01*
X-74975Y-321735D01*
X-74911Y-321235D01*
X-75038Y-320652D01*
X-75481Y-320235D01*
X-75925Y-320068D01*
X-76495D01*
G01X-75925D02*
X-75545Y-319818D01*
X-75228Y-319402D01*
X-75101Y-318902D01*
X-75228Y-318402D01*
X-75545Y-317985D01*
X-76115Y-317735D01*
X-76685Y-317818D01*
X-77255Y-318152D01*
G01X-72471Y-318568D02*
X-72091Y-318068D01*
X-71648Y-317818D01*
X-71141Y-317735D01*
X-70508Y-317902D01*
X-70065Y-318318D01*
X-69938Y-318818D01*
X-70001Y-319318D01*
X-70255Y-319735D01*
X-71521Y-320568D01*
X-72091Y-321152D01*
X-72471Y-321985D01*
X-72598Y-322735D01*
X-69938D01*
G01X-66295D02*
X-66168Y-321652D01*
X-65978Y-320735D01*
X-65725Y-319902D01*
X-65408Y-318985D01*
X-64901Y-317735D01*
X-67435D01*
G01X-61891Y-321068D02*
X-60245D01*
G01X-57171Y-318568D02*
X-56791Y-318068D01*
X-56348Y-317818D01*
X-55841Y-317735D01*
X-55208Y-317902D01*
X-54765Y-318318D01*
X-54638Y-318818D01*
X-54701Y-319318D01*
X-54955Y-319735D01*
X-56221Y-320568D01*
X-56791Y-321152D01*
X-57171Y-321985D01*
X-57298Y-322735D01*
X-54638D01*
G01X-52261Y-321735D02*
X-51881Y-322318D01*
X-51375Y-322652D01*
X-50805Y-322735D01*
X-50298Y-322652D01*
X-49791Y-322235D01*
X-49475Y-321735D01*
X-49411Y-321235D01*
X-49538Y-320652D01*
X-49981Y-320235D01*
X-50425Y-320068D01*
X-50995D01*
G01X-50425D02*
X-50045Y-319818D01*
X-49728Y-319402D01*
X-49601Y-318902D01*
X-49728Y-318402D01*
X-50045Y-317985D01*
X-50615Y-317735D01*
X-51185Y-317818D01*
X-51755Y-318152D01*
G01X-45008Y-322735D02*
Y-317735D01*
X-47351Y-321318D01*
X-44185D01*
G01X-42061Y-321985D02*
X-41681Y-322402D01*
X-41238Y-322652D01*
X-40668Y-322735D01*
X-40098Y-322568D01*
X-39655Y-322235D01*
X-39338Y-321652D01*
X-39275Y-320985D01*
X-39401Y-320318D01*
X-39718Y-319902D01*
X-40161Y-319568D01*
X-40605Y-319485D01*
X-41048Y-319568D01*
X-41618Y-319902D01*
X-41428Y-317735D01*
X-39718D01*
G01X-31671Y-322735D02*
Y-317735D01*
X-29265D01*
G01X-30151Y-320152D02*
X-31671D01*
G01X-26951Y-322735D02*
X-25368Y-317735D01*
X-23785Y-322735D01*
G01X-24355Y-320985D02*
X-26381D01*
G01X-21598Y-322735D02*
X-18938Y-317735D01*
G01X-21598D02*
X-18938Y-322735D01*
G01X-15168Y-322902D02*
X-15295Y-322818D01*
Y-322652D01*
X-15168Y-322568D01*
X-15041Y-322652D01*
Y-322818D01*
X-15168Y-322902D01*
G01Y-320652D02*
X-15295Y-320568D01*
Y-320402D01*
X-15168Y-320318D01*
X-15041Y-320402D01*
Y-320568D01*
X-15168Y-320652D01*
G01X-10385Y-324402D02*
X-11018Y-323568D01*
X-11335Y-322735D01*
Y-319402D01*
X-11018Y-318568D01*
X-10385Y-317735D01*
G01X-4968D02*
X-5475Y-317902D01*
X-5855Y-318318D01*
X-6108Y-318818D01*
X-6298Y-319485D01*
X-6361Y-320235D01*
X-6298Y-320985D01*
X-6108Y-321652D01*
X-5855Y-322152D01*
X-5475Y-322568D01*
X-4968Y-322735D01*
X-4461Y-322568D01*
X-4081Y-322152D01*
X-3828Y-321652D01*
X-3638Y-320985D01*
X-3575Y-320235D01*
X-3638Y-319485D01*
X-3828Y-318818D01*
X-4081Y-318318D01*
X-4461Y-317902D01*
X-4968Y-317735D01*
G01X-1261Y-321735D02*
X-881Y-322318D01*
X-375Y-322652D01*
X195Y-322735D01*
X702Y-322652D01*
X1209Y-322235D01*
X1525Y-321735D01*
X1589Y-321235D01*
X1462Y-320652D01*
X1019Y-320235D01*
X575Y-320068D01*
X5D01*
G01X575D02*
X955Y-319818D01*
X1272Y-319402D01*
X1399Y-318902D01*
X1272Y-318402D01*
X955Y-317985D01*
X385Y-317735D01*
X-185Y-317818D01*
X-755Y-318152D01*
G01X5549Y-324402D02*
X6182Y-323568D01*
X6499Y-322735D01*
Y-319402D01*
X6182Y-318568D01*
X5549Y-317735D01*
G01X8939Y-321735D02*
X9319Y-322318D01*
X9825Y-322652D01*
X10395Y-322735D01*
X10902Y-322652D01*
X11409Y-322235D01*
X11725Y-321735D01*
X11789Y-321235D01*
X11662Y-320652D01*
X11219Y-320235D01*
X10775Y-320068D01*
X10205D01*
G01X10775D02*
X11155Y-319818D01*
X11472Y-319402D01*
X11599Y-318902D01*
X11472Y-318402D01*
X11155Y-317985D01*
X10585Y-317735D01*
X10015Y-317818D01*
X9445Y-318152D01*
G01X14355Y-322152D02*
X14799Y-322568D01*
X15305Y-322735D01*
X15812Y-322568D01*
X16255Y-322068D01*
X16572Y-321318D01*
X16699Y-320568D01*
Y-319652D01*
X16572Y-318902D01*
X16255Y-318235D01*
X15875Y-317902D01*
X15432Y-317735D01*
X14925Y-317902D01*
X14545Y-318235D01*
X14292Y-318735D01*
X14165Y-319402D01*
X14292Y-319985D01*
X14609Y-320568D01*
X14989Y-320902D01*
X15432Y-320985D01*
X15939Y-320818D01*
X16319Y-320402D01*
X16699Y-319652D01*
G01X20405Y-322735D02*
X20532Y-321652D01*
X20722Y-320735D01*
X20975Y-319902D01*
X21292Y-318985D01*
X21799Y-317735D01*
X19265D01*
G01X24809Y-321068D02*
X26455D01*
G01X29339Y-321735D02*
X29719Y-322318D01*
X30225Y-322652D01*
X30795Y-322735D01*
X31302Y-322652D01*
X31809Y-322235D01*
X32125Y-321735D01*
X32189Y-321235D01*
X32062Y-320652D01*
X31619Y-320235D01*
X31175Y-320068D01*
X30605D01*
G01X31175D02*
X31555Y-319818D01*
X31872Y-319402D01*
X31999Y-318902D01*
X31872Y-318402D01*
X31555Y-317985D01*
X30985Y-317735D01*
X30415Y-317818D01*
X29845Y-318152D01*
G01X34629Y-320652D02*
X35072Y-320068D01*
X35452Y-319735D01*
X35959Y-319568D01*
X36402Y-319735D01*
X36719Y-320068D01*
X36972Y-320568D01*
X37035Y-321152D01*
X36972Y-321652D01*
X36719Y-322152D01*
X36339Y-322568D01*
X35895Y-322735D01*
X35389Y-322568D01*
X34945Y-322068D01*
X34692Y-321318D01*
X34629Y-320485D01*
X34755Y-319402D01*
X34945Y-318818D01*
X35262Y-318235D01*
X35705Y-317818D01*
X36149Y-317735D01*
X36592Y-317902D01*
X36909Y-318318D01*
G01X40932Y-322735D02*
Y-317735D01*
X40172Y-318735D01*
G01Y-322735D02*
X41692D01*
G01X46792D02*
Y-317735D01*
X44449Y-321318D01*
X47615D01*
G01X-129168Y-252735D02*
Y-327735D01*
X370832D01*
Y-252735D01*
X-129168D01*
G01X65832D02*
Y-327735D01*
G01Y-302735D02*
X168832D01*
Y-277735D01*
G01X65832D02*
X168832D01*
G01X176339Y-312735D02*
Y-307735D01*
X177605D01*
X178112Y-307985D01*
X178492Y-308318D01*
X178809Y-308818D01*
X179062Y-309402D01*
X179125Y-310235D01*
X179062Y-311068D01*
X178809Y-311652D01*
X178492Y-312152D01*
X178112Y-312485D01*
X177605Y-312735D01*
X176339D01*
G01X181249D02*
X182832Y-307735D01*
X184415Y-312735D01*
G01X183845Y-310985D02*
X181819D01*
G01X187932Y-307735D02*
Y-312735D01*
G01X186475Y-307735D02*
X189389D01*
G01X194299Y-312735D02*
X191765D01*
Y-307735D01*
X194299D01*
G01X193285Y-310152D02*
X191765D01*
G01X198132Y-312902D02*
X198005Y-312818D01*
Y-312652D01*
X198132Y-312568D01*
X198259Y-312652D01*
Y-312818D01*
X198132Y-312902D01*
G01Y-310652D02*
X198005Y-310568D01*
Y-310402D01*
X198132Y-310318D01*
X198259Y-310402D01*
Y-310568D01*
X198132Y-310652D01*
G01X170832Y-252735D02*
Y-327735D01*
G01X168832Y-252735D02*
Y-327735D01*
G01X170832Y-302735D02*
X370832D01*
G01X176465Y-287735D02*
Y-282735D01*
X177985D01*
X178492Y-282985D01*
X178872Y-283568D01*
X178999Y-284235D01*
X178872Y-284902D01*
X178555Y-285402D01*
X177985Y-285652D01*
X176465D01*
G01X181692Y-287902D02*
X183972Y-282735D01*
G01X186475Y-287735D02*
Y-282735D01*
X189389Y-287735D01*
Y-282735D01*
G01X193032Y-287902D02*
X192905Y-287818D01*
Y-287652D01*
X193032Y-287568D01*
X193159Y-287652D01*
Y-287818D01*
X193032Y-287902D01*
G01Y-285652D02*
X192905Y-285568D01*
Y-285402D01*
X193032Y-285318D01*
X193159Y-285402D01*
Y-285568D01*
X193032Y-285652D01*
G01X170832Y-277735D02*
X370832D01*
G01X176465Y-262735D02*
Y-257735D01*
X177985D01*
X178492Y-257985D01*
X178872Y-258568D01*
X178999Y-259235D01*
X178872Y-259902D01*
X178555Y-260402D01*
X177985Y-260652D01*
X176465D01*
G01X181565Y-262735D02*
Y-257735D01*
X183149D01*
X183655Y-257985D01*
X183972Y-258318D01*
X184099Y-258985D01*
X183972Y-259652D01*
X183592Y-260068D01*
X183149Y-260318D01*
X181565D01*
G01X183149D02*
X184099Y-262735D01*
G01X187932D02*
X187425Y-262652D01*
X186982Y-262318D01*
X186602Y-261818D01*
X186349Y-261235D01*
X186222Y-260568D01*
Y-259902D01*
X186349Y-259235D01*
X186602Y-258652D01*
X186982Y-258152D01*
X187425Y-257818D01*
X187932Y-257735D01*
X188439Y-257818D01*
X188882Y-258152D01*
X189262Y-258652D01*
X189515Y-259235D01*
X189642Y-259902D01*
Y-260568D01*
X189515Y-261235D01*
X189262Y-261818D01*
X188882Y-262318D01*
X188439Y-262652D01*
X187932Y-262735D01*
G01X191765Y-261735D02*
X192082Y-262235D01*
X192462Y-262568D01*
X192905Y-262735D01*
X193412Y-262568D01*
X193792Y-262235D01*
X194172Y-261735D01*
X194299Y-261068D01*
Y-257735D01*
G01X199399Y-262735D02*
X196865D01*
Y-257735D01*
X199399D01*
G01X198385Y-260152D02*
X196865D01*
G01X204625Y-258152D02*
X204245Y-257902D01*
X203802Y-257735D01*
X203295D01*
X202725Y-257985D01*
X202282Y-258402D01*
X201965Y-258902D01*
X201712Y-259735D01*
X201649Y-260485D01*
X201775Y-261235D01*
X201965Y-261735D01*
X202345Y-262235D01*
X202789Y-262568D01*
X203232Y-262735D01*
X203675D01*
X204119Y-262568D01*
X204499Y-262318D01*
X204815Y-261985D01*
G01X208332Y-257735D02*
Y-262735D01*
G01X206875Y-257735D02*
X209789D01*
G01X213432Y-262902D02*
X213305Y-262818D01*
Y-262652D01*
X213432Y-262568D01*
X213559Y-262652D01*
Y-262818D01*
X213432Y-262902D01*
G01Y-260652D02*
X213305Y-260568D01*
Y-260402D01*
X213432Y-260318D01*
X213559Y-260402D01*
Y-260568D01*
X213432Y-260652D01*
G01X283832Y-302735D02*
Y-327735D01*
G01X288465Y-305235D02*
Y-310235D01*
X290999D01*
G01X294072Y-305235D02*
X295592D01*
G01X294832D02*
Y-310235D01*
G01X294072D02*
X295592D01*
G01X300439Y-307568D02*
X300692Y-307318D01*
X300882Y-306902D01*
X301009Y-306318D01*
X300882Y-305818D01*
X300629Y-305485D01*
X300185Y-305235D01*
X298475D01*
Y-310235D01*
X300565D01*
X301009Y-309902D01*
X301262Y-309402D01*
X301389Y-308818D01*
X301262Y-308235D01*
X300882Y-307735D01*
X300439Y-307568D01*
X298475D01*
G01X305032Y-310402D02*
X304905Y-310318D01*
Y-310152D01*
X305032Y-310068D01*
X305159Y-310152D01*
Y-310318D01*
X305032Y-310402D01*
G01Y-308152D02*
X304905Y-308068D01*
Y-307902D01*
X305032Y-307818D01*
X305159Y-307902D01*
Y-308068D01*
X305032Y-308152D01*
G01X328832Y-302735D02*
Y-327735D01*
G01X332732Y-305235D02*
Y-310235D01*
G01X331275Y-305235D02*
X334189D01*
G01X337832Y-310235D02*
X337452Y-310152D01*
X337072Y-309818D01*
X336819Y-309235D01*
X336692Y-308568D01*
X336819Y-307902D01*
X337072Y-307318D01*
X337452Y-306985D01*
X337832Y-306902D01*
X338212Y-306985D01*
X338592Y-307318D01*
X338845Y-307902D01*
X338909Y-308568D01*
X338845Y-309235D01*
X338592Y-309818D01*
X338212Y-310152D01*
X337832Y-310235D01*
G01X342932D02*
X342552Y-310152D01*
X342172Y-309818D01*
X341919Y-309235D01*
X341792Y-308568D01*
X341919Y-307902D01*
X342172Y-307318D01*
X342552Y-306985D01*
X342932Y-306902D01*
X343312Y-306985D01*
X343692Y-307318D01*
X343945Y-307902D01*
X344009Y-308568D01*
X343945Y-309235D01*
X343692Y-309818D01*
X343312Y-310152D01*
X342932Y-310235D01*
G01X348032D02*
Y-305235D01*
G01X353132Y-310402D02*
X353005Y-310318D01*
Y-310152D01*
X353132Y-310068D01*
X353259Y-310152D01*
Y-310318D01*
X353132Y-310402D01*
G01Y-308152D02*
X353005Y-308068D01*
Y-307902D01*
X353132Y-307818D01*
X353259Y-307902D01*
Y-308068D01*
X353132Y-308152D01*
G01X328832Y-277735D02*
Y-302735D01*
G01X331465Y-285235D02*
Y-280235D01*
X333049D01*
X333555Y-280485D01*
X333872Y-280818D01*
X333999Y-281485D01*
X333872Y-282152D01*
X333492Y-282568D01*
X333049Y-282818D01*
X331465D01*
G01X333049D02*
X333999Y-285235D01*
G01X339099D02*
X336565D01*
Y-280235D01*
X339099D01*
G01X338085Y-282652D02*
X336565D01*
G01X341349Y-280235D02*
X342932Y-285235D01*
X344515Y-280235D01*
G01X348032Y-285402D02*
X347905Y-285318D01*
Y-285152D01*
X348032Y-285068D01*
X348159Y-285152D01*
Y-285318D01*
X348032Y-285402D01*
G01Y-283152D02*
X347905Y-283068D01*
Y-282902D01*
X348032Y-282818D01*
X348159Y-282902D01*
Y-283068D01*
X348032Y-283152D01*
G01X351592Y-329435D02*
X351672Y-329360D01*
X351732Y-329235D01*
X351772Y-329060D01*
X351732Y-328910D01*
X351652Y-328810D01*
X351512Y-328735D01*
X350972D01*
Y-330235D01*
X351632D01*
X351772Y-330135D01*
X351852Y-329985D01*
X351892Y-329810D01*
X351852Y-329635D01*
X351732Y-329485D01*
X351592Y-329435D01*
X350972D01*
G01X352992Y-330235D02*
Y-329235D01*
G01Y-329410D02*
X352912Y-329310D01*
X352792Y-329260D01*
X352652Y-329235D01*
X352512Y-329285D01*
X352392Y-329385D01*
X352312Y-329535D01*
X352272Y-329735D01*
X352312Y-329935D01*
X352392Y-330085D01*
X352512Y-330185D01*
X352652Y-330235D01*
X352792Y-330210D01*
X352912Y-330135D01*
X352992Y-330035D01*
G01X353532Y-330060D02*
X353632Y-330160D01*
X353772Y-330235D01*
X353892D01*
X354012Y-330185D01*
X354092Y-330110D01*
X354132Y-330010D01*
X354112Y-329860D01*
X354032Y-329785D01*
X353672Y-329635D01*
X353592Y-329460D01*
X353632Y-329335D01*
X353712Y-329260D01*
X353832Y-329235D01*
X353952Y-329260D01*
X354072Y-329335D01*
G01X354732Y-329560D02*
X355372D01*
X355312Y-329385D01*
X355212Y-329285D01*
X355072Y-329235D01*
X354932Y-329260D01*
X354812Y-329335D01*
X354732Y-329510D01*
X354692Y-329660D01*
Y-329810D01*
X354732Y-329960D01*
X354832Y-330110D01*
X354952Y-330210D01*
X355092Y-330235D01*
X355232Y-330185D01*
X355372Y-330035D01*
G01X355872Y-330235D02*
Y-328735D01*
G01Y-329485D02*
X355972Y-329335D01*
X356092Y-329260D01*
X356212Y-329235D01*
X356392Y-329285D01*
X356512Y-329385D01*
X356592Y-329560D01*
Y-329760D01*
X356552Y-329960D01*
X356472Y-330110D01*
X356332Y-330210D01*
X356212Y-330235D01*
X356092Y-330210D01*
X355972Y-330135D01*
X355872Y-330010D01*
G01X357432Y-330235D02*
X357312Y-330210D01*
X357192Y-330110D01*
X357112Y-329935D01*
X357072Y-329735D01*
X357112Y-329535D01*
X357192Y-329360D01*
X357312Y-329260D01*
X357432Y-329235D01*
X357552Y-329260D01*
X357672Y-329360D01*
X357752Y-329535D01*
X357772Y-329735D01*
X357752Y-329935D01*
X357672Y-330110D01*
X357552Y-330210D01*
X357432Y-330235D01*
G01X358992D02*
Y-329235D01*
G01Y-329410D02*
X358912Y-329310D01*
X358792Y-329260D01*
X358652Y-329235D01*
X358512Y-329285D01*
X358392Y-329385D01*
X358312Y-329535D01*
X358272Y-329735D01*
X358312Y-329935D01*
X358392Y-330085D01*
X358512Y-330185D01*
X358652Y-330235D01*
X358792Y-330210D01*
X358912Y-330135D01*
X358992Y-330035D01*
G01X359552Y-330235D02*
Y-329235D01*
G01Y-329435D02*
X359652Y-329335D01*
X359752Y-329260D01*
X359892Y-329235D01*
X359992Y-329260D01*
X360112Y-329335D01*
G01X361392Y-328735D02*
Y-330235D01*
G01Y-330010D02*
X361312Y-330135D01*
X361192Y-330210D01*
X361052Y-330235D01*
X360892Y-330185D01*
X360772Y-330060D01*
X360692Y-329910D01*
X360672Y-329735D01*
X360692Y-329560D01*
X360772Y-329410D01*
X360892Y-329285D01*
X361052Y-329235D01*
X361192Y-329260D01*
X361292Y-329310D01*
X361392Y-329410D01*
G01X363032Y-330235D02*
Y-328735D01*
X363532D01*
X363692Y-328810D01*
X363792Y-328910D01*
X363832Y-329110D01*
X363792Y-329310D01*
X363672Y-329435D01*
X363532Y-329510D01*
X363032D01*
G01X363532D02*
X363832Y-330235D01*
G01X364332Y-329560D02*
X364972D01*
X364912Y-329385D01*
X364812Y-329285D01*
X364672Y-329235D01*
X364532Y-329260D01*
X364412Y-329335D01*
X364332Y-329510D01*
X364292Y-329660D01*
Y-329810D01*
X364332Y-329960D01*
X364432Y-330110D01*
X364552Y-330210D01*
X364692Y-330235D01*
X364832Y-330185D01*
X364972Y-330035D01*
G01X365472Y-329235D02*
X365832Y-330235D01*
X366192Y-329235D01*
G01X367032Y-330285D02*
X366992Y-330260D01*
Y-330210D01*
X367032Y-330185D01*
X367072Y-330210D01*
Y-330260D01*
X367032Y-330285D01*
G01X368192Y-330235D02*
X368232Y-329910D01*
X368292Y-329635D01*
X368372Y-329385D01*
X368472Y-329110D01*
X368632Y-328735D01*
X367832D01*
G01X369592Y-329435D02*
X369672Y-329360D01*
X369732Y-329235D01*
X369772Y-329060D01*
X369732Y-328910D01*
X369652Y-328810D01*
X369512Y-328735D01*
X368972D01*
Y-330235D01*
X369632D01*
X369772Y-330135D01*
X369852Y-329985D01*
X369892Y-329810D01*
X369852Y-329635D01*
X369732Y-329485D01*
X369592Y-329435D01*
X368972D01*
G01X-247901Y-428634D02*
Y1008173D01*
X2091018D01*
Y-428634D01*
X-247901D01*
G01X-115095Y-307460D02*
X-115565Y-307145D01*
X-116113Y-306935D01*
X-116740D01*
X-117445Y-307250D01*
X-117993Y-307775D01*
X-118385Y-308405D01*
X-118698Y-309455D01*
X-118776Y-310400D01*
X-118620Y-311345D01*
X-118385Y-311975D01*
X-117915Y-312605D01*
X-117366Y-313025D01*
X-116818Y-313235D01*
X-116270D01*
X-115721Y-313025D01*
X-115251Y-312710D01*
X-114860Y-312290D01*
G01X-111458Y-306935D02*
X-109578D01*
G01X-110518D02*
Y-313235D01*
G01X-111458D02*
X-109578D01*
G01X-104218Y-306935D02*
Y-313235D01*
G01X-106020Y-306935D02*
X-102416D01*
G01X-97918Y-313235D02*
Y-310400D01*
X-99485Y-306935D01*
G01X-96351D02*
X-97918Y-310400D01*
G01X-87041Y-311975D02*
X-86571Y-312710D01*
X-85945Y-313130D01*
X-85240Y-313235D01*
X-84613Y-313130D01*
X-83986Y-312605D01*
X-83595Y-311975D01*
X-83516Y-311345D01*
X-83673Y-310610D01*
X-84221Y-310085D01*
X-84770Y-309875D01*
X-85475D01*
G01X-84770D02*
X-84300Y-309560D01*
X-83908Y-309035D01*
X-83751Y-308405D01*
X-83908Y-307775D01*
X-84300Y-307250D01*
X-85005Y-306935D01*
X-85710Y-307040D01*
X-86415Y-307460D01*
G01X-80741Y-311975D02*
X-80271Y-312710D01*
X-79645Y-313130D01*
X-78940Y-313235D01*
X-78313Y-313130D01*
X-77686Y-312605D01*
X-77295Y-311975D01*
X-77216Y-311345D01*
X-77373Y-310610D01*
X-77921Y-310085D01*
X-78470Y-309875D01*
X-79175D01*
G01X-78470D02*
X-78000Y-309560D01*
X-77608Y-309035D01*
X-77451Y-308405D01*
X-77608Y-307775D01*
X-78000Y-307250D01*
X-78705Y-306935D01*
X-79410Y-307040D01*
X-80115Y-307460D01*
G01X-74441Y-311975D02*
X-73971Y-312710D01*
X-73345Y-313130D01*
X-72640Y-313235D01*
X-72013Y-313130D01*
X-71386Y-312605D01*
X-70995Y-311975D01*
X-70916Y-311345D01*
X-71073Y-310610D01*
X-71621Y-310085D01*
X-72170Y-309875D01*
X-72875D01*
G01X-72170D02*
X-71700Y-309560D01*
X-71308Y-309035D01*
X-71151Y-308405D01*
X-71308Y-307775D01*
X-71700Y-307250D01*
X-72405Y-306935D01*
X-73110Y-307040D01*
X-73815Y-307460D01*
G01X-66575Y-313235D02*
X-66418Y-311870D01*
X-66183Y-310715D01*
X-65870Y-309665D01*
X-65478Y-308510D01*
X-64851Y-306935D01*
X-67985D01*
G01X-60275Y-313235D02*
X-60118Y-311870D01*
X-59883Y-310715D01*
X-59570Y-309665D01*
X-59178Y-308510D01*
X-58551Y-306935D01*
X-61685D01*
G01X-53975Y-314390D02*
X-53661Y-313025D01*
G01X-47518Y-306935D02*
Y-313235D01*
G01X-49320Y-306935D02*
X-45716D01*
G01X-43176Y-313235D02*
X-41218Y-306935D01*
X-39260Y-313235D01*
G01X-39965Y-311030D02*
X-42471D01*
G01X-35858Y-306935D02*
X-33978D01*
G01X-34918D02*
Y-313235D01*
G01X-35858D02*
X-33978D01*
G01X-30968Y-306935D02*
X-29871Y-313235D01*
X-28618Y-306935D01*
X-27365Y-313235D01*
X-26268Y-306935D01*
G01X-24276Y-313235D02*
X-22318Y-306935D01*
X-20360Y-313235D01*
G01X-21065Y-311030D02*
X-23571D01*
G01X-17820Y-313235D02*
Y-306935D01*
X-14216Y-313235D01*
Y-306935D01*
G01X-3810Y-315335D02*
X-4593Y-314285D01*
X-4985Y-313235D01*
Y-309035D01*
X-4593Y-307985D01*
X-3810Y-306935D01*
G01X7615Y-313235D02*
Y-306935D01*
X9574D01*
X10200Y-307250D01*
X10592Y-307670D01*
X10749Y-308510D01*
X10592Y-309350D01*
X10122Y-309875D01*
X9574Y-310190D01*
X7615D01*
G01X9574D02*
X10749Y-313235D01*
G01X15482Y-313445D02*
X15325Y-313340D01*
Y-313130D01*
X15482Y-313025D01*
X15639Y-313130D01*
Y-313340D01*
X15482Y-313445D01*
G01X21782Y-313235D02*
X21155Y-313130D01*
X20607Y-312710D01*
X20137Y-312080D01*
X19824Y-311345D01*
X19667Y-310505D01*
Y-309665D01*
X19824Y-308825D01*
X20137Y-308090D01*
X20607Y-307460D01*
X21155Y-307040D01*
X21782Y-306935D01*
X22409Y-307040D01*
X22957Y-307460D01*
X23427Y-308090D01*
X23740Y-308825D01*
X23897Y-309665D01*
Y-310505D01*
X23740Y-311345D01*
X23427Y-312080D01*
X22957Y-312710D01*
X22409Y-313130D01*
X21782Y-313235D01*
G01X28082Y-313445D02*
X27925Y-313340D01*
Y-313130D01*
X28082Y-313025D01*
X28239Y-313130D01*
Y-313340D01*
X28082Y-313445D01*
G01X36105Y-307460D02*
X35635Y-307145D01*
X35087Y-306935D01*
X34460D01*
X33755Y-307250D01*
X33207Y-307775D01*
X32815Y-308405D01*
X32502Y-309455D01*
X32424Y-310400D01*
X32580Y-311345D01*
X32815Y-311975D01*
X33285Y-312605D01*
X33834Y-313025D01*
X34382Y-313235D01*
X34930D01*
X35479Y-313025D01*
X35949Y-312710D01*
X36340Y-312290D01*
G01X40682Y-313445D02*
X40525Y-313340D01*
Y-313130D01*
X40682Y-313025D01*
X40839Y-313130D01*
Y-313340D01*
X40682Y-313445D01*
G01X47374Y-315335D02*
X48157Y-314285D01*
X48549Y-313235D01*
Y-309035D01*
X48157Y-307985D01*
X47374Y-306935D01*
G01X-118620Y-293235D02*
Y-286935D01*
X-115016Y-293235D01*
Y-286935D01*
G01X-110518Y-293235D02*
X-111145Y-293130D01*
X-111693Y-292710D01*
X-112163Y-292080D01*
X-112476Y-291345D01*
X-112633Y-290505D01*
Y-289665D01*
X-112476Y-288825D01*
X-112163Y-288090D01*
X-111693Y-287460D01*
X-111145Y-287040D01*
X-110518Y-286935D01*
X-109891Y-287040D01*
X-109343Y-287460D01*
X-108873Y-288090D01*
X-108560Y-288825D01*
X-108403Y-289665D01*
Y-290505D01*
X-108560Y-291345D01*
X-108873Y-292080D01*
X-109343Y-292710D01*
X-109891Y-293130D01*
X-110518Y-293235D01*
G01X-104218Y-293445D02*
X-104375Y-293340D01*
Y-293130D01*
X-104218Y-293025D01*
X-104061Y-293130D01*
Y-293340D01*
X-104218Y-293445D01*
G01X-99406Y-287985D02*
X-98936Y-287355D01*
X-98388Y-287040D01*
X-97761Y-286935D01*
X-96978Y-287145D01*
X-96430Y-287670D01*
X-96273Y-288300D01*
X-96351Y-288930D01*
X-96665Y-289455D01*
X-98231Y-290505D01*
X-98936Y-291240D01*
X-99406Y-292290D01*
X-99563Y-293235D01*
X-96273D01*
G01X-91618D02*
Y-286935D01*
X-92558Y-288195D01*
G01Y-293235D02*
X-90678D01*
G01X-85318D02*
Y-286935D01*
X-86258Y-288195D01*
G01Y-293235D02*
X-84378D01*
G01X-79175Y-294390D02*
X-78861Y-293025D01*
G01X-75068Y-286935D02*
X-73971Y-293235D01*
X-72718Y-286935D01*
X-71465Y-293235D01*
X-70368Y-286935D01*
G01X-64851Y-293235D02*
X-67985D01*
Y-286935D01*
X-64851D01*
G01X-66105Y-289980D02*
X-67985D01*
G01X-61920Y-293235D02*
Y-286935D01*
X-58316Y-293235D01*
Y-286935D01*
G01X-55463Y-293235D02*
Y-286935D01*
G01X-52173D02*
Y-293235D01*
G01Y-290085D02*
X-55463D01*
G01X-49241Y-286935D02*
Y-291450D01*
X-48928Y-292395D01*
X-48301Y-293025D01*
X-47518Y-293235D01*
X-46735Y-293025D01*
X-46108Y-292395D01*
X-45795Y-291450D01*
Y-286935D01*
G01X-43176Y-293235D02*
X-41218Y-286935D01*
X-39260Y-293235D01*
G01X-39965Y-291030D02*
X-42471D01*
G01X-30106Y-287985D02*
X-29636Y-287355D01*
X-29088Y-287040D01*
X-28461Y-286935D01*
X-27678Y-287145D01*
X-27130Y-287670D01*
X-26973Y-288300D01*
X-27051Y-288930D01*
X-27365Y-289455D01*
X-28931Y-290505D01*
X-29636Y-291240D01*
X-30106Y-292290D01*
X-30263Y-293235D01*
X-26973D01*
G01X-24120D02*
Y-286935D01*
X-20516Y-293235D01*
Y-286935D01*
G01X-17741Y-293235D02*
Y-286935D01*
X-16175D01*
X-15548Y-287250D01*
X-15078Y-287670D01*
X-14686Y-288300D01*
X-14373Y-289035D01*
X-14295Y-290085D01*
X-14373Y-291135D01*
X-14686Y-291870D01*
X-15078Y-292500D01*
X-15548Y-292920D01*
X-16175Y-293235D01*
X-17741D01*
G01X-4985D02*
Y-286935D01*
X-3026D01*
X-2400Y-287250D01*
X-2008Y-287670D01*
X-1851Y-288510D01*
X-2008Y-289350D01*
X-2478Y-289875D01*
X-3026Y-290190D01*
X-4985D01*
G01X-3026D02*
X-1851Y-293235D01*
G01X1159D02*
Y-286935D01*
X2725D01*
X3352Y-287250D01*
X3822Y-287670D01*
X4214Y-288300D01*
X4527Y-289035D01*
X4605Y-290085D01*
X4527Y-291135D01*
X4214Y-291870D01*
X3822Y-292500D01*
X3352Y-292920D01*
X2725Y-293235D01*
X1159D01*
G01X9182Y-293445D02*
X9025Y-293340D01*
Y-293130D01*
X9182Y-293025D01*
X9339Y-293130D01*
Y-293340D01*
X9182Y-293445D01*
G01X-116348Y-300085D02*
X-114781D01*
Y-301975D01*
X-115251Y-302605D01*
X-115800Y-303025D01*
X-116583Y-303235D01*
X-117366Y-303025D01*
X-117915Y-302605D01*
X-118385Y-301975D01*
X-118698Y-301240D01*
X-118855Y-300400D01*
Y-299665D01*
X-118698Y-299035D01*
X-118385Y-298300D01*
X-117915Y-297670D01*
X-117445Y-297250D01*
X-116818Y-296935D01*
X-116270D01*
X-115643Y-297145D01*
X-115173Y-297565D01*
G01X-112241Y-296935D02*
Y-301450D01*
X-111928Y-302395D01*
X-111301Y-303025D01*
X-110518Y-303235D01*
X-109735Y-303025D01*
X-109108Y-302395D01*
X-108795Y-301450D01*
Y-296935D01*
G01X-105158D02*
X-103278D01*
G01X-104218D02*
Y-303235D01*
G01X-105158D02*
X-103278D01*
G01X-99563Y-302395D02*
X-98936Y-302920D01*
X-98231Y-303235D01*
X-97605D01*
X-96978Y-302920D01*
X-96508Y-302395D01*
X-96273Y-301660D01*
X-96430Y-300925D01*
X-96821Y-300295D01*
X-97526Y-299875D01*
X-98466Y-299665D01*
X-99015Y-299245D01*
X-99250Y-298510D01*
X-99093Y-297775D01*
X-98701Y-297250D01*
X-98153Y-296935D01*
X-97605D01*
X-97056Y-297145D01*
X-96586Y-297670D01*
G01X-93263Y-303235D02*
Y-296935D01*
G01X-89973D02*
Y-303235D01*
G01Y-300085D02*
X-93263D01*
G01X-87276Y-303235D02*
X-85318Y-296935D01*
X-83360Y-303235D01*
G01X-84065Y-301030D02*
X-86571D01*
G01X-80820Y-303235D02*
Y-296935D01*
X-77216Y-303235D01*
Y-296935D01*
G01X-68141Y-303235D02*
Y-296935D01*
X-66575D01*
X-65948Y-297250D01*
X-65478Y-297670D01*
X-65086Y-298300D01*
X-64773Y-299035D01*
X-64695Y-300085D01*
X-64773Y-301135D01*
X-65086Y-301870D01*
X-65478Y-302500D01*
X-65948Y-302920D01*
X-66575Y-303235D01*
X-68141D01*
G01X-61058Y-296935D02*
X-59178D01*
G01X-60118D02*
Y-303235D01*
G01X-61058D02*
X-59178D01*
G01X-55463Y-302395D02*
X-54836Y-302920D01*
X-54131Y-303235D01*
X-53505D01*
X-52878Y-302920D01*
X-52408Y-302395D01*
X-52173Y-301660D01*
X-52330Y-300925D01*
X-52721Y-300295D01*
X-53426Y-299875D01*
X-54366Y-299665D01*
X-54915Y-299245D01*
X-55150Y-298510D01*
X-54993Y-297775D01*
X-54601Y-297250D01*
X-54053Y-296935D01*
X-53505D01*
X-52956Y-297145D01*
X-52486Y-297670D01*
G01X-47518Y-296935D02*
Y-303235D01*
G01X-49320Y-296935D02*
X-45716D01*
G01X-41218Y-303445D02*
X-41375Y-303340D01*
Y-303130D01*
X-41218Y-303025D01*
X-41061Y-303130D01*
Y-303340D01*
X-41218Y-303445D01*
G01X-35075Y-304390D02*
X-34761Y-303025D01*
G01X-28618Y-296935D02*
Y-303235D01*
G01X-30420Y-296935D02*
X-26816D01*
G01X-24276Y-303235D02*
X-22318Y-296935D01*
X-20360Y-303235D01*
G01X-21065Y-301030D02*
X-23571D01*
G01X-16018Y-303235D02*
X-16645Y-303130D01*
X-17193Y-302710D01*
X-17663Y-302080D01*
X-17976Y-301345D01*
X-18133Y-300505D01*
Y-299665D01*
X-17976Y-298825D01*
X-17663Y-298090D01*
X-17193Y-297460D01*
X-16645Y-297040D01*
X-16018Y-296935D01*
X-15391Y-297040D01*
X-14843Y-297460D01*
X-14373Y-298090D01*
X-14060Y-298825D01*
X-13903Y-299665D01*
Y-300505D01*
X-14060Y-301345D01*
X-14373Y-302080D01*
X-14843Y-302710D01*
X-15391Y-303130D01*
X-16018Y-303235D01*
G01X-9718D02*
Y-300400D01*
X-11285Y-296935D01*
G01X-8151D02*
X-9718Y-300400D01*
G01X-5141Y-296935D02*
Y-301450D01*
X-4828Y-302395D01*
X-4201Y-303025D01*
X-3418Y-303235D01*
X-2635Y-303025D01*
X-2008Y-302395D01*
X-1695Y-301450D01*
Y-296935D01*
G01X924Y-303235D02*
X2882Y-296935D01*
X4840Y-303235D01*
G01X4135Y-301030D02*
X1629D01*
G01X7380Y-303235D02*
Y-296935D01*
X10984Y-303235D01*
Y-296935D01*
G01X-94518Y-282535D02*
X-97038Y-282118D01*
X-99243Y-280452D01*
X-101133Y-277952D01*
X-102393Y-275035D01*
X-103023Y-271702D01*
Y-268368D01*
X-102393Y-265035D01*
X-101133Y-262118D01*
X-99243Y-259619D01*
X-97038Y-257952D01*
X-94518Y-257535D01*
X-91998Y-257952D01*
X-89793Y-259619D01*
X-87903Y-262118D01*
X-86643Y-265035D01*
X-86013Y-268368D01*
Y-271702D01*
X-86643Y-275035D01*
X-87903Y-277952D01*
X-89793Y-280452D01*
X-91998Y-282118D01*
X-94518Y-282535D01*
G01X-91998Y-275868D02*
X-88218Y-282535D01*
G01X-74673Y-265869D02*
Y-277535D01*
X-73413Y-280452D01*
X-71523Y-282118D01*
X-69318Y-282535D01*
X-67113Y-282118D01*
X-65223Y-280452D01*
X-63963Y-277535D01*
G01Y-282535D02*
Y-265869D01*
G01X-38448Y-282535D02*
Y-265869D01*
G01Y-268785D02*
X-39708Y-267119D01*
X-41598Y-266285D01*
X-43803Y-265869D01*
X-46008Y-266702D01*
X-47898Y-268368D01*
X-49158Y-270869D01*
X-49788Y-274202D01*
X-49158Y-277535D01*
X-47898Y-280036D01*
X-46008Y-281702D01*
X-43803Y-282535D01*
X-41598Y-282118D01*
X-39708Y-280869D01*
X-38448Y-279202D01*
G01X-24273Y-282535D02*
Y-265869D01*
G01Y-270035D02*
X-23013Y-267952D01*
X-21123Y-266285D01*
X-18603Y-265869D01*
X-16398Y-266285D01*
X-14508Y-267952D01*
X-13563Y-270869D01*
Y-282535D01*
G01X6282Y-257535D02*
Y-282535D01*
G01X1872Y-265869D02*
X10692D01*
G01X37152Y-282535D02*
Y-265869D01*
G01Y-268785D02*
X35892Y-267119D01*
X34002Y-266285D01*
X31797Y-265869D01*
X29592Y-266702D01*
X27702Y-268368D01*
X26442Y-270869D01*
X25812Y-274202D01*
X26442Y-277535D01*
X27702Y-280036D01*
X29592Y-281702D01*
X31797Y-282535D01*
X34002Y-282118D01*
X35892Y-280869D01*
X37152Y-279202D01*
G01X76832Y-262235D02*
Y-270235D01*
X80832D01*
G01X88632D02*
Y-264902D01*
G01Y-265835D02*
X88232Y-265302D01*
X87632Y-265035D01*
X86932Y-264902D01*
X86232Y-265168D01*
X85632Y-265702D01*
X85232Y-266502D01*
X85032Y-267568D01*
X85232Y-268635D01*
X85632Y-269435D01*
X86232Y-269968D01*
X86932Y-270235D01*
X87632Y-270102D01*
X88232Y-269702D01*
X88632Y-269169D01*
G01X92732Y-272635D02*
X93332Y-272902D01*
X94132Y-272635D01*
X94632Y-272102D01*
X95032Y-271435D01*
X95632Y-269302D01*
X96932Y-264902D01*
G01X93732D02*
X95632Y-269302D01*
G01X101332Y-266635D02*
X104532D01*
X104232Y-265702D01*
X103732Y-265168D01*
X103032Y-264902D01*
X102332Y-265035D01*
X101732Y-265435D01*
X101332Y-266368D01*
X101132Y-267169D01*
Y-267968D01*
X101332Y-268768D01*
X101832Y-269568D01*
X102432Y-270102D01*
X103132Y-270235D01*
X103832Y-269968D01*
X104532Y-269169D01*
G01X109432Y-270235D02*
Y-264902D01*
G01Y-265968D02*
X109932Y-265435D01*
X110432Y-265035D01*
X111132Y-264902D01*
X111632Y-265035D01*
X112232Y-265435D01*
G01X95532Y-320235D02*
Y-312235D01*
X100132Y-320235D01*
Y-312235D01*
G01X105832Y-314902D02*
Y-320235D01*
G01Y-312768D02*
X105632Y-312635D01*
Y-312368D01*
X105832Y-312235D01*
X106032Y-312368D01*
Y-312635D01*
X105832Y-312768D01*
G01X112132Y-320235D02*
Y-314902D01*
G01Y-316235D02*
X112532Y-315568D01*
X113132Y-315035D01*
X113932Y-314902D01*
X114632Y-315035D01*
X115232Y-315568D01*
X115532Y-316502D01*
Y-320235D01*
G01X123632D02*
Y-314902D01*
G01Y-315835D02*
X123232Y-315302D01*
X122632Y-315035D01*
X121932Y-314902D01*
X121232Y-315168D01*
X120632Y-315702D01*
X120232Y-316502D01*
X120032Y-317568D01*
X120232Y-318635D01*
X120632Y-319435D01*
X121232Y-319968D01*
X121932Y-320235D01*
X122632Y-320102D01*
X123232Y-319702D01*
X123632Y-319169D01*
G01X90232Y-295235D02*
Y-287235D01*
X92832Y-293902D01*
X95432Y-287235D01*
Y-295235D01*
G01X98332D02*
X100832Y-287235D01*
X103332Y-295235D01*
G01X102432Y-292435D02*
X99232D01*
G01X106732Y-294169D02*
X107532Y-294835D01*
X108432Y-295235D01*
X109232D01*
X110032Y-294835D01*
X110632Y-294169D01*
X110932Y-293235D01*
X110732Y-292302D01*
X110232Y-291502D01*
X109332Y-290968D01*
X108132Y-290702D01*
X107432Y-290168D01*
X107132Y-289235D01*
X107332Y-288302D01*
X107832Y-287635D01*
X108532Y-287235D01*
X109232D01*
X109932Y-287502D01*
X110532Y-288168D01*
G01X114632Y-295235D02*
Y-287235D01*
G01X118432D02*
X114632Y-292169D01*
G01X119032Y-295235D02*
X116332Y-289902D01*
G01X123532Y-292568D02*
X126132D01*
G01X132832Y-287235D02*
Y-295235D01*
G01X130532Y-287235D02*
X135132D01*
G01X140832Y-295235D02*
X140032Y-295102D01*
X139332Y-294568D01*
X138732Y-293768D01*
X138332Y-292835D01*
X138132Y-291768D01*
Y-290702D01*
X138332Y-289635D01*
X138732Y-288702D01*
X139332Y-287902D01*
X140032Y-287368D01*
X140832Y-287235D01*
X141632Y-287368D01*
X142332Y-287902D01*
X142932Y-288702D01*
X143332Y-289635D01*
X143532Y-290702D01*
Y-291768D01*
X143332Y-292835D01*
X142932Y-293768D01*
X142332Y-294568D01*
X141632Y-295102D01*
X140832Y-295235D01*
G01X146832D02*
Y-287235D01*
X149232D01*
X150032Y-287635D01*
X150632Y-288568D01*
X150832Y-289635D01*
X150632Y-290702D01*
X150132Y-291502D01*
X149232Y-291902D01*
X146832D01*
G01X203432Y-313568D02*
X204032Y-312768D01*
X204732Y-312368D01*
X205532Y-312235D01*
X206532Y-312502D01*
X207232Y-313168D01*
X207432Y-313968D01*
X207332Y-314769D01*
X206932Y-315435D01*
X204932Y-316768D01*
X204032Y-317702D01*
X203432Y-319035D01*
X203232Y-320235D01*
X207432D01*
G01X213332Y-312235D02*
X212532Y-312502D01*
X211932Y-313168D01*
X211532Y-313968D01*
X211232Y-315035D01*
X211132Y-316235D01*
X211232Y-317435D01*
X211532Y-318502D01*
X211932Y-319302D01*
X212532Y-319968D01*
X213332Y-320235D01*
X214132Y-319968D01*
X214732Y-319302D01*
X215132Y-318502D01*
X215432Y-317435D01*
X215532Y-316235D01*
X215432Y-315035D01*
X215132Y-313968D01*
X214732Y-313168D01*
X214132Y-312502D01*
X213332Y-312235D01*
G01X219432Y-313568D02*
X220032Y-312768D01*
X220732Y-312368D01*
X221532Y-312235D01*
X222532Y-312502D01*
X223232Y-313168D01*
X223432Y-313968D01*
X223332Y-314769D01*
X222932Y-315435D01*
X220932Y-316768D01*
X220032Y-317702D01*
X219432Y-319035D01*
X219232Y-320235D01*
X223432D01*
G01X227432Y-313568D02*
X228032Y-312768D01*
X228732Y-312368D01*
X229532Y-312235D01*
X230532Y-312502D01*
X231232Y-313168D01*
X231432Y-313968D01*
X231332Y-314769D01*
X230932Y-315435D01*
X228932Y-316768D01*
X228032Y-317702D01*
X227432Y-319035D01*
X227232Y-320235D01*
X231432D01*
G01X235532Y-320502D02*
X239132Y-312235D01*
G01X245332Y-320235D02*
Y-312235D01*
X244132Y-313835D01*
G01Y-320235D02*
X246532D01*
G01X251432Y-313568D02*
X252032Y-312768D01*
X252732Y-312368D01*
X253532Y-312235D01*
X254532Y-312502D01*
X255232Y-313168D01*
X255432Y-313968D01*
X255332Y-314769D01*
X254932Y-315435D01*
X252932Y-316768D01*
X252032Y-317702D01*
X251432Y-319035D01*
X251232Y-320235D01*
X255432D01*
G01X259532Y-320502D02*
X263132Y-312235D01*
G01X269332D02*
X268532Y-312502D01*
X267932Y-313168D01*
X267532Y-313968D01*
X267232Y-315035D01*
X267132Y-316235D01*
X267232Y-317435D01*
X267532Y-318502D01*
X267932Y-319302D01*
X268532Y-319968D01*
X269332Y-320235D01*
X270132Y-319968D01*
X270732Y-319302D01*
X271132Y-318502D01*
X271432Y-317435D01*
X271532Y-316235D01*
X271432Y-315035D01*
X271132Y-313968D01*
X270732Y-313168D01*
X270132Y-312502D01*
X269332Y-312235D01*
G01X275632Y-319302D02*
X276332Y-319968D01*
X277132Y-320235D01*
X277932Y-319968D01*
X278632Y-319169D01*
X279132Y-317968D01*
X279332Y-316768D01*
Y-315302D01*
X279132Y-314102D01*
X278632Y-313035D01*
X278032Y-312502D01*
X277332Y-312235D01*
X276532Y-312502D01*
X275932Y-313035D01*
X275532Y-313835D01*
X275332Y-314902D01*
X275532Y-315835D01*
X276032Y-316768D01*
X276632Y-317302D01*
X277332Y-317435D01*
X278132Y-317169D01*
X278732Y-316502D01*
X279332Y-315302D01*
G01X205632Y-295235D02*
Y-287235D01*
X207632D01*
X208432Y-287635D01*
X209032Y-288168D01*
X209532Y-288968D01*
X209932Y-289902D01*
X210032Y-291235D01*
X209932Y-292568D01*
X209532Y-293502D01*
X209032Y-294302D01*
X208432Y-294835D01*
X207632Y-295235D01*
X205632D01*
G01X213332D02*
X215832Y-287235D01*
X218332Y-295235D01*
G01X217432Y-292435D02*
X214232D01*
G01X223832Y-287235D02*
X223032Y-287502D01*
X222432Y-288168D01*
X222032Y-288968D01*
X221732Y-290035D01*
X221632Y-291235D01*
X221732Y-292435D01*
X222032Y-293502D01*
X222432Y-294302D01*
X223032Y-294968D01*
X223832Y-295235D01*
X224632Y-294968D01*
X225232Y-294302D01*
X225632Y-293502D01*
X225932Y-292435D01*
X226032Y-291235D01*
X225932Y-290035D01*
X225632Y-288968D01*
X225232Y-288168D01*
X224632Y-287502D01*
X223832Y-287235D01*
G01X229932Y-295235D02*
Y-287235D01*
X233732D01*
G01X232332Y-291102D02*
X229932D01*
G01X239832Y-287235D02*
X239032Y-287502D01*
X238432Y-288168D01*
X238032Y-288968D01*
X237732Y-290035D01*
X237632Y-291235D01*
X237732Y-292435D01*
X238032Y-293502D01*
X238432Y-294302D01*
X239032Y-294968D01*
X239832Y-295235D01*
X240632Y-294968D01*
X241232Y-294302D01*
X241632Y-293502D01*
X241932Y-292435D01*
X242032Y-291235D01*
X241932Y-290035D01*
X241632Y-288968D01*
X241232Y-288168D01*
X240632Y-287502D01*
X239832Y-287235D01*
G01X247832D02*
Y-295235D01*
G01X245532Y-287235D02*
X250132D01*
G01X255832Y-295235D02*
Y-291635D01*
X253832Y-287235D01*
G01X257832D02*
X255832Y-291635D01*
G01X264632Y-290968D02*
X265032Y-290568D01*
X265332Y-289902D01*
X265532Y-288968D01*
X265332Y-288168D01*
X264932Y-287635D01*
X264232Y-287235D01*
X261532D01*
Y-295235D01*
X264832D01*
X265532Y-294702D01*
X265932Y-293902D01*
X266132Y-292968D01*
X265932Y-292035D01*
X265332Y-291235D01*
X264632Y-290968D01*
X261532D01*
G01X273032Y-295235D02*
Y-287235D01*
X269332Y-292968D01*
X274332D01*
G01X277632Y-295235D02*
Y-287235D01*
X279632D01*
X280432Y-287635D01*
X281032Y-288168D01*
X281532Y-288968D01*
X281932Y-289902D01*
X282032Y-291235D01*
X281932Y-292568D01*
X281532Y-293502D01*
X281032Y-294302D01*
X280432Y-294835D01*
X279632Y-295235D01*
X277632D01*
G01X287832Y-287235D02*
X287032Y-287502D01*
X286432Y-288168D01*
X286032Y-288968D01*
X285732Y-290035D01*
X285632Y-291235D01*
X285732Y-292435D01*
X286032Y-293502D01*
X286432Y-294302D01*
X287032Y-294968D01*
X287832Y-295235D01*
X288632Y-294968D01*
X289232Y-294302D01*
X289632Y-293502D01*
X289932Y-292435D01*
X290032Y-291235D01*
X289932Y-290035D01*
X289632Y-288968D01*
X289232Y-288168D01*
X288632Y-287502D01*
X287832Y-287235D01*
G01X233432Y-270235D02*
Y-262235D01*
X237232D01*
G01X235832Y-266102D02*
X233432D01*
G01X243332Y-262235D02*
X242532Y-262502D01*
X241932Y-263168D01*
X241532Y-263968D01*
X241232Y-265035D01*
X241132Y-266235D01*
X241232Y-267435D01*
X241532Y-268502D01*
X241932Y-269302D01*
X242532Y-269968D01*
X243332Y-270235D01*
X244132Y-269968D01*
X244732Y-269302D01*
X245132Y-268502D01*
X245432Y-267435D01*
X245532Y-266235D01*
X245432Y-265035D01*
X245132Y-263968D01*
X244732Y-263168D01*
X244132Y-262502D01*
X243332Y-262235D01*
G01X251332D02*
Y-270235D01*
G01X249032Y-262235D02*
X253632D01*
G01X256332Y-272902D02*
X262332D01*
G01X265332Y-270235D02*
Y-262235D01*
X267732D01*
X268532Y-262635D01*
X269132Y-263568D01*
X269332Y-264635D01*
X269132Y-265702D01*
X268632Y-266502D01*
X267732Y-266902D01*
X265332D01*
G01X272832Y-270235D02*
X275332Y-262235D01*
X277832Y-270235D01*
G01X276932Y-267435D02*
X273732D01*
G01X281032Y-270235D02*
Y-262235D01*
X285632Y-270235D01*
Y-262235D01*
G01X293332Y-270235D02*
X289332D01*
Y-262235D01*
X293332D01*
G01X291732Y-266102D02*
X289332D01*
G01X297332Y-262235D02*
Y-270235D01*
X301332D01*
G01X304332Y-272902D02*
X310332D01*
G01X316132Y-265968D02*
X316532Y-265568D01*
X316832Y-264902D01*
X317032Y-263968D01*
X316832Y-263168D01*
X316432Y-262635D01*
X315732Y-262235D01*
X313032D01*
Y-270235D01*
X316332D01*
X317032Y-269702D01*
X317432Y-268902D01*
X317632Y-267968D01*
X317432Y-267035D01*
X316832Y-266235D01*
X316132Y-265968D01*
X313032D01*
G01X321132Y-270235D02*
Y-262235D01*
X323132D01*
X323932Y-262635D01*
X324532Y-263168D01*
X325032Y-263968D01*
X325432Y-264902D01*
X325532Y-266235D01*
X325432Y-267568D01*
X325032Y-268502D01*
X324532Y-269302D01*
X323932Y-269835D01*
X323132Y-270235D01*
X321132D01*
G01X291832Y-323235D02*
Y-315235D01*
X290632Y-316835D01*
G01Y-323235D02*
X293032D01*
G01X297932Y-319902D02*
X298632Y-318968D01*
X299232Y-318435D01*
X300032Y-318168D01*
X300732Y-318435D01*
X301232Y-318968D01*
X301632Y-319768D01*
X301732Y-320702D01*
X301632Y-321502D01*
X301232Y-322302D01*
X300632Y-322968D01*
X299932Y-323235D01*
X299132Y-322968D01*
X298432Y-322169D01*
X298032Y-320968D01*
X297932Y-319635D01*
X298132Y-317902D01*
X298432Y-316968D01*
X298932Y-316035D01*
X299632Y-315368D01*
X300332Y-315235D01*
X301032Y-315502D01*
X301532Y-316168D01*
G01X307832Y-323502D02*
X307632Y-323368D01*
Y-323102D01*
X307832Y-322968D01*
X308032Y-323102D01*
Y-323368D01*
X307832Y-323502D01*
G01X313932Y-319902D02*
X314632Y-318968D01*
X315232Y-318435D01*
X316032Y-318168D01*
X316732Y-318435D01*
X317232Y-318968D01*
X317632Y-319768D01*
X317732Y-320702D01*
X317632Y-321502D01*
X317232Y-322302D01*
X316632Y-322968D01*
X315932Y-323235D01*
X315132Y-322968D01*
X314432Y-322169D01*
X314032Y-320968D01*
X313932Y-319635D01*
X314132Y-317902D01*
X314432Y-316968D01*
X314932Y-316035D01*
X315632Y-315368D01*
X316332Y-315235D01*
X317032Y-315502D01*
X317532Y-316168D01*
G01X336832Y-323235D02*
Y-315235D01*
X335632Y-316835D01*
G01Y-323235D02*
X338032D01*
G01X344632D02*
X344832Y-321502D01*
X345132Y-320035D01*
X345532Y-318702D01*
X346032Y-317235D01*
X346832Y-315235D01*
X342832D01*
G01X352832Y-323502D02*
X352632Y-323368D01*
Y-323102D01*
X352832Y-322968D01*
X353032Y-323102D01*
Y-323368D01*
X352832Y-323502D01*
G01X358932Y-316568D02*
X359532Y-315768D01*
X360232Y-315368D01*
X361032Y-315235D01*
X362032Y-315502D01*
X362732Y-316168D01*
X362932Y-316968D01*
X362832Y-317769D01*
X362432Y-318435D01*
X360432Y-319768D01*
X359532Y-320702D01*
X358932Y-322035D01*
X358732Y-323235D01*
X362932D01*
G01X356632Y-298235D02*
Y-290235D01*
X358632D01*
X359432Y-290635D01*
X360032Y-291168D01*
X360532Y-291968D01*
X360932Y-292902D01*
X361032Y-294235D01*
X360932Y-295568D01*
X360532Y-296502D01*
X360032Y-297302D01*
X359432Y-297835D01*
X358632Y-298235D01*
X356632D01*
M02*
